(kicad_pcb
	(version 20260206)
	(generator "pcbnew")
	(generator_version "10.0")
	(general
		(thickness 1.6)
		(legacy_teardrops no)
	)
	(paper "A4")
	(title_block
		(title "v2-pdb — ms_pdb_v2.brd")
		(comment 1 "Open CloudServer (Microsoft) / footprints 151-156 of 348")
	)
	(layers
		(0 "F.Cu" signal "TOP")
		(4 "In1.Cu" signal "GND")
		(6 "In2.Cu" signal "IN1")
		(8 "In3.Cu" signal "VCC")
		(10 "In4.Cu" signal "VCC1")
		(12 "In5.Cu" signal "IN2")
		(14 "In6.Cu" signal "GND1")
		(2 "B.Cu" signal "BOTTOM")
		(9 "F.Adhes" user "F.Adhesive")
		(11 "B.Adhes" user "B.Adhesive")
		(13 "F.Paste" user "Package Geometry/Pastemask Top")
		(15 "B.Paste" user "Package Geometry/Pastemask Bottom")
		(5 "F.SilkS" user "Ref Des/Silkscreen Top")
		(7 "B.SilkS" user "Ref Des/Silkscreen Bottom")
		(1 "F.Mask" user "Board Geometry/Soldermask Top")
		(3 "B.Mask" user "Board Geometry/Soldermask Bottom")
		(17 "Dwgs.User" user "User.Drawings")
		(19 "Cmts.User" user "User.Comments")
		(21 "Eco1.User" user "User.Eco1")
		(23 "Eco2.User" user "User.Eco2")
		(25 "Edge.Cuts" user "Board Geometry/Outline")
		(27 "Margin" user)
		(31 "F.CrtYd" user "Package Geometry/Place Bound Top")
		(29 "B.CrtYd" user "Package Geometry/Place Bound Bottom")
		(35 "F.Fab" user "Ref Des/Assembly Top")
		(33 "B.Fab" user "Ref Des/Assembly Bottom")
	)
	(footprint ""
		(layer "F.Cu")
		(at 39.459154 -111.174022 -90)
		(property "Reference" "R90"
			(at -1.104392 -0.0254 90)
			(unlocked yes)
			(layer "F.SilkS")
			(effects
				(font
					(size 0.7874 0.5842)
					(thickness 0.1524)
				)
				(justify left)
			)
		)
		(property "Value" ""
			(at 0 0 270)
			(layer "F.Fab")
			(effects
				(font
					(size 1.27 1.27)
				)
			)
		)
		(duplicate_pad_numbers_are_jumpers no)
		(fp_line
			(start -0.7874 0.4064)
			(end -0.7874 -0.4064)
			(stroke
				(width 0.1524)
				(type default)
			)
			(layer "F.SilkS")
		)
		(fp_line
			(start 0.7874 0.4064)
			(end -0.7874 0.4064)
			(stroke
				(width 0.1524)
				(type default)
			)
			(layer "F.SilkS")
		)
		(fp_line
			(start -0.7874 -0.4064)
			(end 0.7874 -0.4064)
			(stroke
				(width 0.1524)
				(type default)
			)
			(layer "F.SilkS")
		)
		(fp_line
			(start 0.7874 -0.4064)
			(end 0.7874 0.4064)
			(stroke
				(width 0.1524)
				(type default)
			)
			(layer "F.SilkS")
		)
		(fp_poly
			(pts
				(xy -0.508 0.2794) (xy -0.508 0.2286) (xy -0.635 0.2286) (xy -0.635 -0.254) (xy -0.5334 -0.254)
				(xy -0.5334 -0.2794) (xy 0.5334 -0.2794) (xy 0.5334 -0.254) (xy 0.635 -0.254) (xy 0.635 0.254) (xy 0.5334 0.254)
				(xy 0.5334 0.2794)
			)
			(stroke
				(width 0)
				(type default)
			)
			(fill no)
			(layer "F.CrtYd")
		)
		(pad "1" smd rect
			(at 0.40005 0 270)
			(size 0.4572 0.508)
			(layers "F.Cu" "F.Mask" "F.Paste")
			(net "PSU2_REMOTE_P")
		)
		(pad "2" smd rect
			(at -0.40005 0 270)
			(size 0.4572 0.508)
			(layers "F.Cu" "F.Mask" "F.Paste")
			(net "PSU2_REMOTE_R_P")
		)
	)
	(footprint ""
		(layer "F.Cu")
		(at 50.083466 -482.70668 180)
		(property "Reference" "CE21"
			(at -4.321048 2.407666 0)
			(unlocked yes)
			(layer "F.SilkS")
			(effects
				(font
					(size 0.7874 0.5842)
					(thickness 0.1524)
				)
				(justify left)
			)
		)
		(property "Value" ""
			(at 0 0 180)
			(layer "F.Fab")
			(effects
				(font
					(size 1.27 1.27)
				)
			)
		)
		(duplicate_pad_numbers_are_jumpers no)
		(fp_line
			(start 0 -4.2672)
			(end 0 4.2672)
			(stroke
				(width 0.1524)
				(type default)
			)
			(layer "F.SilkS")
		)
		(fp_circle
			(center 0 0)
			(end -4.2672 0)
			(stroke
				(width 0.1524)
				(type default)
			)
			(fill no)
			(layer "F.SilkS")
		)
		(fp_poly
			(pts
				(arc
					(start 0 -4.2672)
					(mid 4.2672 0)
					(end 0 4.2672)
				)
			)
			(stroke
				(width 0)
				(type default)
			)
			(fill yes)
			(layer "F.SilkS")
		)
		(fp_poly
			(pts
				(xy -2.5146 -0.762) (xy -0.9906 -0.762) (xy -0.9906 0.762) (xy -2.5146 0.762)
			)
			(stroke
				(width 0)
				(type default)
			)
			(fill no)
			(layer "B.CrtYd")
		)
		(fp_poly
			(pts
				(arc
					(start 1.7526 0.762)
					(mid 2.291415 -0.538815)
					(end 0.9906 0)
				)
				(arc
					(start 0.9906 0.0254)
					(mid 1.206345 0.546255)
					(end 1.7272 0.762)
				)
			)
			(stroke
				(width 0)
				(type default)
			)
			(fill no)
			(layer "B.CrtYd")
		)
		(fp_poly
			(pts
				(arc
					(start -4.2672 0)
					(mid 4.2672 0)
					(end -4.2672 0)
				)
			)
			(stroke
				(width 0)
				(type default)
			)
			(fill no)
			(layer "F.CrtYd")
		)
		(fp_circle
			(center 0 0)
			(end -4.2672 0)
			(stroke
				(width 0.1)
				(type default)
			)
			(fill no)
			(layer "F.Fab")
		)
		(fp_text user "+"
			(at -5.960364 -0.43053 180)
			(unlocked yes)
			(layer "F.SilkS")
			(effects
				(font
					(size 1.905 1.4224)
					(thickness 0.1524)
				)
				(justify left)
			)
		)
		(fp_text user "+"
			(at -5.6642 -0.34925 180)
			(unlocked yes)
			(layer "F.Fab")
			(effects
				(font
					(size 1.905 1.4224)
					(thickness 0.000001)
				)
				(justify left)
			)
		)
		(pad "1" thru_hole rect
			(at -1.75006 0 180)
			(size 1.397 1.397)
			(drill 0.9144)
			(layers "*.Cu" "*.Mask")
			(remove_unused_layers no)
			(net "P12V")
			(clearance 0.0127)
			(thermal_gap 0.0127)
			(padstack
				(mode front_inner_back)
				(layer "Inner"
					(shape circle)
					(size 1.397 1.397)
					(clearance 0.0127)
				)
				(layer "B.Cu"
					(shape rect)
					(size 1.397 1.397)
					(clearance 0.0127)
				)
			)
		)
		(pad "2" thru_hole circle
			(at 1.75006 0 180)
			(size 1.397 1.397)
			(drill 0.9144)
			(layers "*.Cu" "*.Mask")
			(remove_unused_layers no)
			(net "GND")
			(clearance 0.0127)
			(thermal_gap 0.0127)
		)
	)
	(footprint ""
		(layer "F.Cu")
		(at 20.388326 -177.804572 -90)
		(property "Reference" "R158"
			(at 1.054354 4.446778 90)
			(unlocked yes)
			(layer "F.SilkS")
			(effects
				(font
					(size 0.7874 0.5842)
					(thickness 0.1524)
				)
				(justify left)
			)
		)
		(property "Value" ""
			(at 0 0 270)
			(layer "F.Fab")
			(effects
				(font
					(size 1.27 1.27)
				)
			)
		)
		(duplicate_pad_numbers_are_jumpers no)
		(fp_line
			(start -0.7874 0.4064)
			(end -0.7874 -0.4064)
			(stroke
				(width 0.1524)
				(type default)
			)
			(layer "F.SilkS")
		)
		(fp_line
			(start 0.7874 0.4064)
			(end -0.7874 0.4064)
			(stroke
				(width 0.1524)
				(type default)
			)
			(layer "F.SilkS")
		)
		(fp_line
			(start -0.7874 -0.4064)
			(end 0.7874 -0.4064)
			(stroke
				(width 0.1524)
				(type default)
			)
			(layer "F.SilkS")
		)
		(fp_line
			(start 0.7874 -0.4064)
			(end 0.7874 0.4064)
			(stroke
				(width 0.1524)
				(type default)
			)
			(layer "F.SilkS")
		)
		(fp_poly
			(pts
				(xy -0.508 0.2794) (xy -0.508 0.2286) (xy -0.635 0.2286) (xy -0.635 -0.254) (xy -0.5334 -0.254)
				(xy -0.5334 -0.2794) (xy 0.5334 -0.2794) (xy 0.5334 -0.254) (xy 0.635 -0.254) (xy 0.635 0.254) (xy 0.5334 0.254)
				(xy 0.5334 0.2794)
			)
			(stroke
				(width 0)
				(type default)
			)
			(fill no)
			(layer "F.CrtYd")
		)
		(pad "1" smd rect
			(at 0.40005 0 270)
			(size 0.4572 0.508)
			(layers "F.Cu" "F.Mask" "F.Paste")
			(net "P12V")
		)
		(pad "2" smd rect
			(at -0.40005 0 270)
			(size 0.4572 0.508)
			(layers "F.Cu" "F.Mask" "F.Paste")
			(net "N42263600")
		)
	)
	(footprint ""
		(layer "F.Cu")
		(at 26.068274 -187.950348)
		(property "Reference" "R71"
			(at -3.997198 0.128524 0)
			(unlocked yes)
			(layer "F.SilkS")
			(effects
				(font
					(size 0.7874 0.5842)
					(thickness 0.1524)
				)
				(justify left)
			)
		)
		(property "Value" ""
			(at 0 0 0)
			(layer "F.Fab")
			(effects
				(font
					(size 1.27 1.27)
				)
			)
		)
		(duplicate_pad_numbers_are_jumpers no)
		(fp_line
			(start -0.7874 -0.4064)
			(end 0.7874 -0.4064)
			(stroke
				(width 0.1524)
				(type default)
			)
			(layer "F.SilkS")
		)
		(fp_line
			(start -0.7874 0.4064)
			(end -0.7874 -0.4064)
			(stroke
				(width 0.1524)
				(type default)
			)
			(layer "F.SilkS")
		)
		(fp_line
			(start 0.7874 -0.4064)
			(end 0.7874 0.4064)
			(stroke
				(width 0.1524)
				(type default)
			)
			(layer "F.SilkS")
		)
		(fp_line
			(start 0.7874 0.4064)
			(end -0.7874 0.4064)
			(stroke
				(width 0.1524)
				(type default)
			)
			(layer "F.SilkS")
		)
		(fp_poly
			(pts
				(xy -0.508 0.2794) (xy -0.508 0.2286) (xy -0.635 0.2286) (xy -0.635 -0.254) (xy -0.5334 -0.254)
				(xy -0.5334 -0.2794) (xy 0.5334 -0.2794) (xy 0.5334 -0.254) (xy 0.635 -0.254) (xy 0.635 0.254) (xy 0.5334 0.254)
				(xy 0.5334 0.2794)
			)
			(stroke
				(width 0)
				(type default)
			)
			(fill no)
			(layer "F.CrtYd")
		)
		(pad "1" smd rect
			(at 0.40005 0)
			(size 0.4572 0.508)
			(layers "F.Cu" "F.Mask" "F.Paste")
			(net "PSU3_PS_KILL")
		)
		(pad "2" smd rect
			(at -0.40005 0)
			(size 0.4572 0.508)
			(layers "F.Cu" "F.Mask" "F.Paste")
			(net "GND")
		)
	)
	(footprint ""
		(layer "F.Cu")
		(at 39.858188 -287.573212 180)
		(property "Reference" "R15"
			(at -1.140714 0.062738 0)
			(unlocked yes)
			(layer "F.SilkS")
			(effects
				(font
					(size 0.7874 0.5842)
					(thickness 0.1524)
				)
				(justify left)
			)
		)
		(property "Value" ""
			(at 0 0 180)
			(layer "F.Fab")
			(effects
				(font
					(size 1.27 1.27)
				)
			)
		)
		(duplicate_pad_numbers_are_jumpers no)
		(fp_line
			(start 0.7874 0.4064)
			(end -0.7874 0.4064)
			(stroke
				(width 0.1524)
				(type default)
			)
			(layer "F.SilkS")
		)
		(fp_line
			(start 0.7874 -0.4064)
			(end 0.7874 0.4064)
			(stroke
				(width 0.1524)
				(type default)
			)
			(layer "F.SilkS")
		)
		(fp_line
			(start -0.7874 0.4064)
			(end -0.7874 -0.4064)
			(stroke
				(width 0.1524)
				(type default)
			)
			(layer "F.SilkS")
		)
		(fp_line
			(start -0.7874 -0.4064)
			(end 0.7874 -0.4064)
			(stroke
				(width 0.1524)
				(type default)
			)
			(layer "F.SilkS")
		)
		(fp_poly
			(pts
				(xy -0.508 0.2794) (xy -0.508 0.2286) (xy -0.635 0.2286) (xy -0.635 -0.254) (xy -0.5334 -0.254)
				(xy -0.5334 -0.2794) (xy 0.5334 -0.2794) (xy 0.5334 -0.254) (xy 0.635 -0.254) (xy 0.635 0.254) (xy 0.5334 0.254)
				(xy 0.5334 0.2794)
			)
			(stroke
				(width 0)
				(type default)
			)
			(fill no)
			(layer "F.CrtYd")
		)
		(pad "1" smd rect
			(at 0.40005 0 180)
			(size 0.4572 0.508)
			(layers "F.Cu" "F.Mask" "F.Paste")
			(net "PSU4_REMOTE_P")
		)
		(pad "2" smd rect
			(at -0.40005 0 180)
			(size 0.4572 0.508)
			(layers "F.Cu" "F.Mask" "F.Paste")
			(net "P12V")
		)
	)
	(footprint ""
		(layer "F.Cu")
		(at 13.964666 -70.993 -90)
		(property "Reference" "J23"
			(at -4.44754 5.76199 0)
			(unlocked yes)
			(layer "F.SilkS")
			(effects
				(font
					(size 0.7874 0.5842)
					(thickness 0.1524)
				)
				(justify left)
			)
		)
		(property "Value" ""
			(at 0 0 270)
			(layer "F.Fab")
			(effects
				(font
					(size 1.27 1.27)
				)
			)
		)
		(duplicate_pad_numbers_are_jumpers no)
		(fp_line
			(start -3.370072 12.830048)
			(end -3.370072 -3.81)
			(stroke
				(width 0.1524)
				(type default)
			)
			(layer "F.SilkS")
		)
		(fp_line
			(start 12.260072 12.830048)
			(end -3.370072 12.830048)
			(stroke
				(width 0.1524)
				(type default)
			)
			(layer "F.SilkS")
		)
		(fp_line
			(start -3.370072 -3.81)
			(end 12.260072 -3.81)
			(stroke
				(width 0.1524)
				(type default)
			)
			(layer "F.SilkS")
		)
		(fp_line
			(start 12.260072 -3.81)
			(end 12.260072 12.830048)
			(stroke
				(width 0.1524)
				(type default)
			)
			(layer "F.SilkS")
		)
		(fp_poly
			(pts
				(xy -3.560064 -0.233934) (xy -4.459224 0.215646) (xy -4.459224 -0.683514)
			)
			(stroke
				(width 0)
				(type default)
			)
			(fill yes)
			(layer "F.SilkS")
		)
		(fp_poly
			(pts
				(xy -0.762 0.762) (xy 8.382 0.762) (xy 8.382 -1.8034) (xy 9.652 -1.8034) (xy 9.652 -3.302) (xy 0.508 -3.302)
				(xy 0.508 -0.762) (xy -0.762 -0.762)
			)
			(stroke
				(width 0)
				(type default)
			)
			(fill no)
			(layer "B.CrtYd")
		)
		(fp_poly
			(pts
				(arc
					(start -1.27 4.4196)
					(mid -1.27 8.2804)
					(end -1.27 4.4196)
				)
			)
			(stroke
				(width 0)
				(type default)
			)
			(fill no)
			(layer "B.CrtYd")
		)
		(fp_poly
			(pts
				(arc
					(start 10.16 4.4196)
					(mid 10.16 8.2804)
					(end 10.16 4.4196)
				)
			)
			(stroke
				(width 0)
				(type default)
			)
			(fill no)
			(layer "B.CrtYd")
		)
		(fp_poly
			(pts
				(xy -3.370072 12.830048) (xy 12.260072 12.830048) (xy 12.260072 -3.81) (xy -3.370072 -3.81)
			)
			(stroke
				(width 0)
				(type default)
			)
			(fill no)
			(layer "F.CrtYd")
		)
		(fp_line
			(start -3.370072 12.830048)
			(end -3.370072 -3.81)
			(stroke
				(width 0.1)
				(type default)
			)
			(layer "F.Fab")
		)
		(fp_line
			(start 12.260072 12.830048)
			(end -3.370072 12.830048)
			(stroke
				(width 0.1)
				(type default)
			)
			(layer "F.Fab")
		)
		(fp_line
			(start -3.370072 -3.81)
			(end 12.260072 -3.81)
			(stroke
				(width 0.1)
				(type default)
			)
			(layer "F.Fab")
		)
		(fp_line
			(start 12.260072 -3.81)
			(end 12.260072 12.830048)
			(stroke
				(width 0.1)
				(type default)
			)
			(layer "F.Fab")
		)
		(fp_poly
			(pts
				(xy -3.576828 0) (xy -5.0038 0.713486) (xy -5.0038 -0.713486)
			)
			(stroke
				(width 0)
				(type default)
			)
			(fill yes)
			(layer "F.Fab")
		)
		(fp_text user "1"
			(at -4.26085 0.74803 0)
			(unlocked yes)
			(layer "F.SilkS")
			(effects
				(font
					(size 0.7874 0.5842)
					(thickness 0.1524)
				)
			)
		)
		(fp_text user "7"
			(at 12.93241 -0.070866 0)
			(unlocked yes)
			(layer "F.SilkS")
			(effects
				(font
					(size 0.7874 0.5842)
					(thickness 0.1524)
				)
			)
		)
		(fp_text user "2"
			(at -4.078224 -2.544826 0)
			(unlocked yes)
			(layer "F.SilkS")
			(effects
				(font
					(size 0.7874 0.5842)
					(thickness 0.1524)
				)
			)
		)
		(fp_text user "8"
			(at 12.901676 -2.696718 0)
			(unlocked yes)
			(layer "F.SilkS")
			(effects
				(font
					(size 0.7874 0.5842)
					(thickness 0.1524)
				)
			)
		)
		(fp_text user "1"
			(at -1.526286 0.037846 0)
			(unlocked yes)
			(layer "B.SilkS")
			(effects
				(font
					(size 0.7874 0.5842)
					(thickness 0.1524)
				)
				(justify mirror)
			)
		)
		(fp_text user "7"
			(at 9.031732 -0.064516 0)
			(unlocked yes)
			(layer "B.SilkS")
			(effects
				(font
					(size 0.7874 0.5842)
					(thickness 0.1524)
				)
				(justify mirror)
			)
		)
		(fp_text user "8"
			(at 10.25652 -2.445766 0)
			(unlocked yes)
			(layer "B.SilkS")
			(effects
				(font
					(size 0.7874 0.5842)
					(thickness 0.1524)
				)
				(justify mirror)
			)
		)
		(fp_text user "2"
			(at -0.230886 -2.629154 0)
			(unlocked yes)
			(layer "B.SilkS")
			(effects
				(font
					(size 0.7874 0.5842)
					(thickness 0.1524)
				)
				(justify mirror)
			)
		)
		(fp_text user "7"
			(at 8.8138 0.238252 270)
			(unlocked yes)
			(layer "B.Fab")
			(effects
				(font
					(size 0.7874 0.5842)
					(thickness 0.000001)
				)
				(justify mirror)
			)
		)
		(fp_text user "1"
			(at -1.2954 0.085852 270)
			(unlocked yes)
			(layer "B.Fab")
			(effects
				(font
					(size 0.7874 0.5842)
					(thickness 0.000001)
				)
				(justify mirror)
			)
		)
		(fp_text user "8"
			(at 10.0838 -2.403348 270)
			(unlocked yes)
			(layer "B.Fab")
			(effects
				(font
					(size 0.7874 0.5842)
					(thickness 0.000001)
				)
				(justify mirror)
			)
		)
		(fp_text user "2"
			(at 0 -2.581148 270)
			(unlocked yes)
			(layer "B.Fab")
			(effects
				(font
					(size 0.7874 0.5842)
					(thickness 0.000001)
				)
				(justify mirror)
			)
		)
		(fp_text user "7"
			(at 12.7762 -0.091948 270)
			(unlocked yes)
			(layer "F.Fab")
			(effects
				(font
					(size 0.7874 0.5842)
					(thickness 0.000001)
				)
			)
		)
		(fp_text user "1"
			(at -3.9116 -0.930148 270)
			(unlocked yes)
			(layer "F.Fab")
			(effects
				(font
					(size 0.7874 0.5842)
					(thickness 0.000001)
				)
			)
		)
		(fp_text user "2"
			(at -3.9624 -2.428748 270)
			(unlocked yes)
			(layer "F.Fab")
			(effects
				(font
					(size 0.7874 0.5842)
					(thickness 0.000001)
				)
			)
		)
		(fp_text user "8"
			(at 12.7762 -2.555748 270)
			(unlocked yes)
			(layer "F.Fab")
			(effects
				(font
					(size 0.7874 0.5842)
					(thickness 0.000001)
				)
			)
		)
		(pad "" np_thru_hole circle
			(at -1.27 6.35 270)
			(size 3.3528 3.3528)
			(drill 3.3528)
			(layers "*.Cu" "*.Mask")
			(clearance 0.381)
			(thermal_gap 0.381)
		)
		(pad "" np_thru_hole circle
			(at 10.16 6.35 270)
			(size 3.3528 3.3528)
			(drill 3.3528)
			(layers "*.Cu" "*.Mask")
			(clearance 0.381)
			(thermal_gap 0.381)
		)
		(pad "1" thru_hole rect
			(at 0 0 270)
			(size 1.397 1.397)
			(drill 0.9906)
			(layers "*.Cu" "*.Mask")
			(remove_unused_layers no)
			(net "UART_RTS_P5_L_N")
			(clearance 0.0508)
			(thermal_gap 0.0508)
			(padstack
				(mode front_inner_back)
				(layer "Inner"
					(shape circle)
					(size 1.397 1.397)
					(clearance 0.0508)
				)
				(layer "B.Cu"
					(shape rect)
					(size 1.397 1.397)
					(clearance 0.0508)
				)
			)
		)
		(pad "2" thru_hole circle
			(at 1.27 -2.54 270)
			(size 1.397 1.397)
			(drill 0.9906)
			(layers "*.Cu" "*.Mask")
			(remove_unused_layers no)
			(net "UART_DSR_P5_L_N")
			(clearance 0.0508)
			(thermal_gap 0.0508)
		)
		(pad "3" thru_hole circle
			(at 2.54 0 270)
			(size 1.397 1.397)
			(drill 0.9906)
			(layers "*.Cu" "*.Mask")
			(remove_unused_layers no)
			(net "UART_RX_P5_L")
			(clearance 0.0508)
			(thermal_gap 0.0508)
		)
		(pad "4" thru_hole circle
			(at 3.81 -2.54 270)
			(size 1.397 1.397)
			(drill 0.9906)
			(layers "*.Cu" "*.Mask")
			(remove_unused_layers no)
			(net "UART_RI_P5_L_N")
			(clearance 0.0508)
			(thermal_gap 0.0508)
		)
		(pad "5" thru_hole circle
			(at 5.08 0 270)
			(size 1.397 1.397)
			(drill 0.9906)
			(layers "*.Cu" "*.Mask")
			(remove_unused_layers no)
			(net "GND")
			(clearance 0.0508)
			(thermal_gap 0.0508)
		)
		(pad "6" thru_hole circle
			(at 6.35 -2.54 270)
			(size 1.397 1.397)
			(drill 0.9906)
			(layers "*.Cu" "*.Mask")
			(remove_unused_layers no)
			(net "UART_TX_P5_L")
			(clearance 0.0508)
			(thermal_gap 0.0508)
		)
		(pad "7" thru_hole circle
			(at 7.62 0 270)
			(size 1.397 1.397)
			(drill 0.9906)
			(layers "*.Cu" "*.Mask")
			(remove_unused_layers no)
			(net "UART_DTR_P5_L_N")
			(clearance 0.0508)
			(thermal_gap 0.0508)
		)
		(pad "8" thru_hole circle
			(at 8.89 -2.54 270)
			(size 1.397 1.397)
			(drill 0.9906)
			(layers "*.Cu" "*.Mask")
			(remove_unused_layers no)
			(net "UART_CTS_P5_L_N")
			(clearance 0.0508)
			(thermal_gap 0.0508)
		)
		(zone
			(layers "F.Cu" "B.Cu" "In1.Cu" "In2.Cu" "In3.Cu" "In4.Cu" "In5.Cu" "In6.Cu")
			(hatch none 0.5)
			(connect_pads
				(clearance 0)
			)
			(min_thickness 0.25)
			(keepout
				(tracks not_allowed)
				(vias allowed)
				(pads allowed)
				(copperpour not_allowed)
				(footprints allowed)
			)
			(placement
				(enabled no)
				(sheetname "")
			)
			(fill
				(thermal_gap 0.5)
				(thermal_bridge_width 0.5)
				(island_removal_mode 0)
			)
			(polygon
				(pts
					(arc
						(start 9.697466 -72.263)
						(mid 5.531866 -72.263)
						(end 9.697466 -72.263)
					)
				)
			)
		)
		(zone
			(layers "F.Cu" "B.Cu" "In1.Cu" "In2.Cu" "In3.Cu" "In4.Cu" "In5.Cu" "In6.Cu")
			(hatch none 0.5)
			(connect_pads
				(clearance 0)
			)
			(min_thickness 0.25)
			(keepout
				(tracks not_allowed)
				(vias allowed)
				(pads allowed)
				(copperpour not_allowed)
				(footprints allowed)
			)
			(placement
				(enabled no)
				(sheetname "")
			)
			(fill
				(thermal_gap 0.5)
				(thermal_bridge_width 0.5)
				(island_removal_mode 0)
			)
			(polygon
				(pts
					(arc
						(start 9.697466 -60.833)
						(mid 5.531866 -60.833)
						(end 9.697466 -60.833)
					)
				)
			)
		)
	)
)
